(kicad_pcb
	(version 20260206)
	(generator "pcbnew")
	(generator_version "10.0")
	(general
		(thickness 1.6)
		(legacy_teardrops no)
	)
	(paper "A4")
	(title_block
		(title "03242023_DA0F0TMBIJ0_F0T_Motherboard_J_brd_V01_OCP.brd")
		(comment 1 "Grand Teton / footprint 1229 of 6105 (J4), pads 113-224 of 291")
	)
	(layers
		(0 "F.Cu" signal "TOP")
		(4 "In1.Cu" signal "GND")
		(6 "In2.Cu" signal "IN1")
		(8 "In3.Cu" signal "GND1")
		(10 "In4.Cu" signal "IN2")
		(12 "In5.Cu" signal "GND2")
		(14 "In6.Cu" signal "IN3")
		(16 "In7.Cu" signal "GND3")
		(18 "In8.Cu" signal "VCC")
		(20 "In9.Cu" signal "VCC1")
		(22 "In10.Cu" signal "GND4")
		(24 "In11.Cu" signal "IN4")
		(26 "In12.Cu" signal "GND5")
		(28 "In13.Cu" signal "IN5")
		(30 "In14.Cu" signal "GND6")
		(32 "In15.Cu" signal "IN6")
		(34 "In16.Cu" signal "GND7")
		(2 "B.Cu" signal "BOTTOM")
		(9 "F.Adhes" user "F.Adhesive")
		(11 "B.Adhes" user "B.Adhesive")
		(13 "F.Paste" user "Package Geometry/Pastemask Top")
		(15 "B.Paste" user "Package Geometry/Pastemask Bottom")
		(5 "F.SilkS" user "Ref Des/Silkscreen Top")
		(7 "B.SilkS" user "Ref Des/Silkscreen Bottom")
		(1 "F.Mask" user "Board Geometry/Soldermask Top")
		(3 "B.Mask" user "Board Geometry/Soldermask Bottom")
		(17 "Dwgs.User" user "User.Drawings")
		(19 "Cmts.User" user "User.Comments")
		(21 "Eco1.User" user "User.Eco1")
		(23 "Eco2.User" user "User.Eco2")
		(25 "Edge.Cuts" user "Board Geometry/Outline")
		(27 "Margin" user)
		(31 "F.CrtYd" user "Package Geometry/Place Bound Top")
		(29 "B.CrtYd" user "Package Geometry/Place Bound Bottom")
		(35 "F.Fab" user "Ref Des/Assembly Top")
		(33 "B.Fab" user "Ref Des/Assembly Bottom")
	)
	(footprint ""
		(layer "F.Cu")
		(at 295.849548 -258.091686)
		(property "Reference" "J4"
			(at -3.683 -81.702148 0)
			(unlocked yes)
			(layer "F.SilkS")
			(effects
				(font
					(size 0.7874 0.5842)
					(thickness 0.1524)
				)
				(justify left)
			)
		)
		(property "Value" ""
			(at 0 0 0)
			(layer "F.Fab")
			(effects
				(font
					(size 1.27 1.27)
				)
			)
		)
		(duplicate_pad_numbers_are_jumpers no)
		(pad "113" smd rect
			(at -2.050034 36.975034 270)
			(size 0.519938 1.4986)
			(layers "F.Cu" "F.Mask" "F.Paste")
			(net "M_B_CPU0_SB_DQ<9>")
		)
		(pad "114" smd rect
			(at -2.050034 37.824918 270)
			(size 0.519938 1.4986)
			(layers "F.Cu" "F.Mask" "F.Paste")
			(net "GND")
		)
		(pad "115" smd rect
			(at -2.050034 38.675056 270)
			(size 0.519938 1.4986)
			(layers "F.Cu" "F.Mask" "F.Paste")
			(net "M_B_CPU0_SB_DQS_DP<1>")
		)
		(pad "116" smd rect
			(at -2.050034 39.52494 270)
			(size 0.519938 1.4986)
			(layers "F.Cu" "F.Mask" "F.Paste")
			(net "M_B_CPU0_SB_DQS_DN<1>")
		)
		(pad "117" smd rect
			(at -2.050034 40.375078 270)
			(size 0.519938 1.4986)
			(layers "F.Cu" "F.Mask" "F.Paste")
			(net "GND")
		)
		(pad "118" smd rect
			(at -2.050034 41.224962 270)
			(size 0.519938 1.4986)
			(layers "F.Cu" "F.Mask" "F.Paste")
			(net "M_B_CPU0_SB_DQ<12>")
		)
		(pad "119" smd rect
			(at -2.050034 42.0751 270)
			(size 0.519938 1.4986)
			(layers "F.Cu" "F.Mask" "F.Paste")
			(net "GND")
		)
		(pad "120" smd rect
			(at -2.050034 42.924984 270)
			(size 0.519938 1.4986)
			(layers "F.Cu" "F.Mask" "F.Paste")
			(net "M_B_CPU0_SB_DQ<13>")
		)
		(pad "121" smd rect
			(at -2.050034 43.775122 270)
			(size 0.519938 1.4986)
			(layers "F.Cu" "F.Mask" "F.Paste")
			(net "GND")
		)
		(pad "122" smd rect
			(at -2.050034 44.625006 270)
			(size 0.519938 1.4986)
			(layers "F.Cu" "F.Mask" "F.Paste")
			(net "M_B_CPU0_SB_DQ<16>")
		)
		(pad "123" smd rect
			(at -2.050034 45.47489 270)
			(size 0.519938 1.4986)
			(layers "F.Cu" "F.Mask" "F.Paste")
			(net "GND")
		)
		(pad "124" smd rect
			(at -2.050034 46.325028 270)
			(size 0.519938 1.4986)
			(layers "F.Cu" "F.Mask" "F.Paste")
			(net "M_B_CPU0_SB_DQ<17>")
		)
		(pad "125" smd rect
			(at -2.050034 47.174912 270)
			(size 0.519938 1.4986)
			(layers "F.Cu" "F.Mask" "F.Paste")
			(net "GND")
		)
		(pad "126" smd rect
			(at -2.050034 48.02505 270)
			(size 0.519938 1.4986)
			(layers "F.Cu" "F.Mask" "F.Paste")
			(net "M_B_CPU0_SB_DQS_DP<2>")
		)
		(pad "127" smd rect
			(at -2.050034 48.874934 270)
			(size 0.519938 1.4986)
			(layers "F.Cu" "F.Mask" "F.Paste")
			(net "M_B_CPU0_SB_DQS_DN<2>")
		)
		(pad "128" smd rect
			(at -2.050034 49.725072 270)
			(size 0.519938 1.4986)
			(layers "F.Cu" "F.Mask" "F.Paste")
			(net "GND")
		)
		(pad "129" smd rect
			(at -2.050034 50.574956 270)
			(size 0.519938 1.4986)
			(layers "F.Cu" "F.Mask" "F.Paste")
			(net "M_B_CPU0_SB_DQ<20>")
		)
		(pad "130" smd rect
			(at -2.050034 51.425094 270)
			(size 0.519938 1.4986)
			(layers "F.Cu" "F.Mask" "F.Paste")
			(net "GND")
		)
		(pad "131" smd rect
			(at -2.050034 52.274978 270)
			(size 0.519938 1.4986)
			(layers "F.Cu" "F.Mask" "F.Paste")
			(net "M_B_CPU0_SB_DQ<21>")
		)
		(pad "132" smd rect
			(at -2.050034 53.125116 270)
			(size 0.519938 1.4986)
			(layers "F.Cu" "F.Mask" "F.Paste")
			(net "GND")
		)
		(pad "133" smd rect
			(at -2.050034 53.975 270)
			(size 0.519938 1.4986)
			(layers "F.Cu" "F.Mask" "F.Paste")
			(net "M_B_CPU0_SB_DQ<24>")
		)
		(pad "134" smd rect
			(at -2.050034 54.824884 270)
			(size 0.519938 1.4986)
			(layers "F.Cu" "F.Mask" "F.Paste")
			(net "GND")
		)
		(pad "135" smd rect
			(at -2.050034 55.675022 270)
			(size 0.519938 1.4986)
			(layers "F.Cu" "F.Mask" "F.Paste")
			(net "M_B_CPU0_SB_DQ<25>")
		)
		(pad "136" smd rect
			(at -2.050034 56.524906 270)
			(size 0.519938 1.4986)
			(layers "F.Cu" "F.Mask" "F.Paste")
			(net "GND")
		)
		(pad "137" smd rect
			(at -2.050034 57.375044 270)
			(size 0.519938 1.4986)
			(layers "F.Cu" "F.Mask" "F.Paste")
			(net "M_B_CPU0_SB_DQS_DP<3>")
		)
		(pad "138" smd rect
			(at -2.050034 58.224928 270)
			(size 0.519938 1.4986)
			(layers "F.Cu" "F.Mask" "F.Paste")
			(net "M_B_CPU0_SB_DQS_DN<3>")
		)
		(pad "139" smd rect
			(at -2.050034 59.075066 270)
			(size 0.519938 1.4986)
			(layers "F.Cu" "F.Mask" "F.Paste")
			(net "GND")
		)
		(pad "140" smd rect
			(at -2.050034 59.92495 270)
			(size 0.519938 1.4986)
			(layers "F.Cu" "F.Mask" "F.Paste")
			(net "M_B_CPU0_SB_DQ<28>")
		)
		(pad "141" smd rect
			(at -2.050034 60.775088 270)
			(size 0.519938 1.4986)
			(layers "F.Cu" "F.Mask" "F.Paste")
			(net "GND")
		)
		(pad "142" smd rect
			(at -2.050034 61.624972 270)
			(size 0.519938 1.4986)
			(layers "F.Cu" "F.Mask" "F.Paste")
			(net "M_B_CPU0_SB_DQ<29>")
		)
		(pad "143" smd rect
			(at -2.050034 62.47511 270)
			(size 0.519938 1.4986)
			(layers "F.Cu" "F.Mask" "F.Paste")
			(net "GND")
		)
		(pad "144" smd rect
			(at -2.050034 63.324994 270)
			(size 0.519938 1.4986)
			(layers "F.Cu" "F.Mask" "F.Paste")
			(net "TP_CHB_CPU0_DIMM2_FRU_1")
		)
		(pad "145" smd rect
			(at 2.050034 -63.324994 270)
			(size 0.519938 1.4986)
			(layers "F.Cu" "F.Mask" "F.Paste")
			(net "P12V_S3_AUX_CPU0_NVDIMM")
		)
		(pad "146" smd rect
			(at 2.050034 -62.47511 270)
			(size 0.519938 1.4986)
			(layers "F.Cu" "F.Mask" "F.Paste")
			(net "P12V_S3_AUX_CPU0_NVDIMM")
		)
		(pad "147" smd rect
			(at 2.050034 -61.624972 270)
			(size 0.519938 1.4986)
			(layers "F.Cu" "F.Mask" "F.Paste")
			(net "PWRGD_CHB_CPU0_DIMM2")
		)
		(pad "148" smd rect
			(at 2.050034 -60.775088 270)
			(size 0.519938 1.4986)
			(layers "F.Cu" "F.Mask" "F.Paste")
			(net "PD_CHB_CPU0_DIMM2_SAA")
		)
		(pad "149" smd rect
			(at 2.050034 -59.92495 270)
			(size 0.519938 1.4986)
			(layers "F.Cu" "F.Mask" "F.Paste")
			(net "TP_CHB_CPU0_DIMM2_FRU_2")
		)
		(pad "150" smd rect
			(at 2.050034 -59.075066 270)
			(size 0.519938 1.4986)
			(layers "F.Cu" "F.Mask" "F.Paste")
			(net "TP_CHB_CPU0_DIMM2_FRU_3")
		)
		(pad "151" smd rect
			(at 2.050034 -58.224928 270)
			(size 0.519938 1.4986)
			(layers "F.Cu" "F.Mask" "F.Paste")
			(net "GND")
		)
		(pad "152" smd rect
			(at 2.050034 -57.375044 270)
			(size 0.519938 1.4986)
			(layers "F.Cu" "F.Mask" "F.Paste")
			(net "M_B_CPU0_SA_DQ<2>")
		)
		(pad "153" smd rect
			(at 2.050034 -56.524906 270)
			(size 0.519938 1.4986)
			(layers "F.Cu" "F.Mask" "F.Paste")
			(net "GND")
		)
		(pad "154" smd rect
			(at 2.050034 -55.675022 270)
			(size 0.519938 1.4986)
			(layers "F.Cu" "F.Mask" "F.Paste")
			(net "M_B_CPU0_SA_DQ<3>")
		)
		(pad "155" smd rect
			(at 2.050034 -54.824884 270)
			(size 0.519938 1.4986)
			(layers "F.Cu" "F.Mask" "F.Paste")
			(net "GND")
		)
		(pad "156" smd rect
			(at 2.050034 -53.975 270)
			(size 0.519938 1.4986)
			(layers "F.Cu" "F.Mask" "F.Paste")
			(net "M_B_CPU0_SA_DQS_DN<5>")
		)
		(pad "157" smd rect
			(at 2.050034 -53.125116 270)
			(size 0.519938 1.4986)
			(layers "F.Cu" "F.Mask" "F.Paste")
			(net "M_B_CPU0_SA_DQS_DP<5>")
		)
		(pad "158" smd rect
			(at 2.050034 -52.274978 270)
			(size 0.519938 1.4986)
			(layers "F.Cu" "F.Mask" "F.Paste")
			(net "GND")
		)
		(pad "159" smd rect
			(at 2.050034 -51.425094 270)
			(size 0.519938 1.4986)
			(layers "F.Cu" "F.Mask" "F.Paste")
			(net "M_B_CPU0_SA_DQ<6>")
		)
		(pad "160" smd rect
			(at 2.050034 -50.574956 270)
			(size 0.519938 1.4986)
			(layers "F.Cu" "F.Mask" "F.Paste")
			(net "GND")
		)
		(pad "161" smd rect
			(at 2.050034 -49.725072 270)
			(size 0.519938 1.4986)
			(layers "F.Cu" "F.Mask" "F.Paste")
			(net "M_B_CPU0_SA_DQ<7>")
		)
		(pad "162" smd rect
			(at 2.050034 -48.874934 270)
			(size 0.519938 1.4986)
			(layers "F.Cu" "F.Mask" "F.Paste")
			(net "GND")
		)
		(pad "163" smd rect
			(at 2.050034 -48.02505 270)
			(size 0.519938 1.4986)
			(layers "F.Cu" "F.Mask" "F.Paste")
			(net "M_B_CPU0_SA_DQ<10>")
		)
		(pad "164" smd rect
			(at 2.050034 -47.174912 270)
			(size 0.519938 1.4986)
			(layers "F.Cu" "F.Mask" "F.Paste")
			(net "GND")
		)
		(pad "165" smd rect
			(at 2.050034 -46.325028 270)
			(size 0.519938 1.4986)
			(layers "F.Cu" "F.Mask" "F.Paste")
			(net "M_B_CPU0_SA_DQ<11>")
		)
		(pad "166" smd rect
			(at 2.050034 -45.47489 270)
			(size 0.519938 1.4986)
			(layers "F.Cu" "F.Mask" "F.Paste")
			(net "GND")
		)
		(pad "167" smd rect
			(at 2.050034 -44.625006 270)
			(size 0.519938 1.4986)
			(layers "F.Cu" "F.Mask" "F.Paste")
			(net "M_B_CPU0_SA_DQS_DN<6>")
		)
		(pad "168" smd rect
			(at 2.050034 -43.775122 270)
			(size 0.519938 1.4986)
			(layers "F.Cu" "F.Mask" "F.Paste")
			(net "M_B_CPU0_SA_DQS_DP<6>")
		)
		(pad "169" smd rect
			(at 2.050034 -42.924984 270)
			(size 0.519938 1.4986)
			(layers "F.Cu" "F.Mask" "F.Paste")
			(net "GND")
		)
		(pad "170" smd rect
			(at 2.050034 -42.0751 270)
			(size 0.519938 1.4986)
			(layers "F.Cu" "F.Mask" "F.Paste")
			(net "M_B_CPU0_SA_DQ<14>")
		)
		(pad "171" smd rect
			(at 2.050034 -41.224962 270)
			(size 0.519938 1.4986)
			(layers "F.Cu" "F.Mask" "F.Paste")
			(net "GND")
		)
		(pad "172" smd rect
			(at 2.050034 -40.375078 270)
			(size 0.519938 1.4986)
			(layers "F.Cu" "F.Mask" "F.Paste")
			(net "M_B_CPU0_SA_DQ<15>")
		)
		(pad "173" smd rect
			(at 2.050034 -39.52494 270)
			(size 0.519938 1.4986)
			(layers "F.Cu" "F.Mask" "F.Paste")
			(net "GND")
		)
		(pad "174" smd rect
			(at 2.050034 -38.675056 270)
			(size 0.519938 1.4986)
			(layers "F.Cu" "F.Mask" "F.Paste")
			(net "M_B_CPU0_SA_DQ<18>")
		)
		(pad "175" smd rect
			(at 2.050034 -37.824918 270)
			(size 0.519938 1.4986)
			(layers "F.Cu" "F.Mask" "F.Paste")
			(net "GND")
		)
		(pad "176" smd rect
			(at 2.050034 -36.975034 270)
			(size 0.519938 1.4986)
			(layers "F.Cu" "F.Mask" "F.Paste")
			(net "M_B_CPU0_SA_DQ<19>")
		)
		(pad "177" smd rect
			(at 2.050034 -36.124896 270)
			(size 0.519938 1.4986)
			(layers "F.Cu" "F.Mask" "F.Paste")
			(net "GND")
		)
		(pad "178" smd rect
			(at 2.050034 -35.275012 270)
			(size 0.519938 1.4986)
			(layers "F.Cu" "F.Mask" "F.Paste")
			(net "M_B_CPU0_SA_DQS_DN<7>")
		)
		(pad "179" smd rect
			(at 2.050034 -34.425128 270)
			(size 0.519938 1.4986)
			(layers "F.Cu" "F.Mask" "F.Paste")
			(net "M_B_CPU0_SA_DQS_DP<7>")
		)
		(pad "180" smd rect
			(at 2.050034 -33.57499 270)
			(size 0.519938 1.4986)
			(layers "F.Cu" "F.Mask" "F.Paste")
			(net "GND")
		)
		(pad "181" smd rect
			(at 2.050034 -32.725106 270)
			(size 0.519938 1.4986)
			(layers "F.Cu" "F.Mask" "F.Paste")
			(net "M_B_CPU0_SA_DQ<22>")
		)
		(pad "182" smd rect
			(at 2.050034 -31.874968 270)
			(size 0.519938 1.4986)
			(layers "F.Cu" "F.Mask" "F.Paste")
			(net "GND")
		)
		(pad "183" smd rect
			(at 2.050034 -31.025084 270)
			(size 0.519938 1.4986)
			(layers "F.Cu" "F.Mask" "F.Paste")
			(net "M_B_CPU0_SA_DQ<23>")
		)
		(pad "184" smd rect
			(at 2.050034 -30.174946 270)
			(size 0.519938 1.4986)
			(layers "F.Cu" "F.Mask" "F.Paste")
			(net "GND")
		)
		(pad "185" smd rect
			(at 2.050034 -29.325062 270)
			(size 0.519938 1.4986)
			(layers "F.Cu" "F.Mask" "F.Paste")
			(net "M_B_CPU0_SA_DQ<26>")
		)
		(pad "186" smd rect
			(at 2.050034 -28.474924 270)
			(size 0.519938 1.4986)
			(layers "F.Cu" "F.Mask" "F.Paste")
			(net "GND")
		)
		(pad "187" smd rect
			(at 2.050034 -27.62504 270)
			(size 0.519938 1.4986)
			(layers "F.Cu" "F.Mask" "F.Paste")
			(net "M_B_CPU0_SA_DQ<27>")
		)
		(pad "188" smd rect
			(at 2.050034 -26.774902 270)
			(size 0.519938 1.4986)
			(layers "F.Cu" "F.Mask" "F.Paste")
			(net "GND")
		)
		(pad "189" smd rect
			(at 2.050034 -25.925018 270)
			(size 0.519938 1.4986)
			(layers "F.Cu" "F.Mask" "F.Paste")
			(net "M_B_CPU0_SA_DQS_DN<8>")
		)
		(pad "190" smd rect
			(at 2.050034 -25.07488 270)
			(size 0.519938 1.4986)
			(layers "F.Cu" "F.Mask" "F.Paste")
			(net "M_B_CPU0_SA_DQS_DP<8>")
		)
		(pad "191" smd rect
			(at 2.050034 -24.224996 270)
			(size 0.519938 1.4986)
			(layers "F.Cu" "F.Mask" "F.Paste")
			(net "GND")
		)
		(pad "192" smd rect
			(at 2.050034 -23.375112 270)
			(size 0.519938 1.4986)
			(layers "F.Cu" "F.Mask" "F.Paste")
			(net "M_B_CPU0_SA_DQ<30>")
		)
		(pad "193" smd rect
			(at 2.050034 -22.524974 270)
			(size 0.519938 1.4986)
			(layers "F.Cu" "F.Mask" "F.Paste")
			(net "GND")
		)
		(pad "194" smd rect
			(at 2.050034 -21.67509 270)
			(size 0.519938 1.4986)
			(layers "F.Cu" "F.Mask" "F.Paste")
			(net "M_B_CPU0_SA_DQ<31>")
		)
		(pad "195" smd rect
			(at 2.050034 -20.824952 270)
			(size 0.519938 1.4986)
			(layers "F.Cu" "F.Mask" "F.Paste")
			(net "GND")
		)
		(pad "196" smd rect
			(at 2.050034 -19.975068 270)
			(size 0.519938 1.4986)
			(layers "F.Cu" "F.Mask" "F.Paste")
			(net "M_B_CPU0_SA_CB<2>")
		)
		(pad "197" smd rect
			(at 2.050034 -19.12493 270)
			(size 0.519938 1.4986)
			(layers "F.Cu" "F.Mask" "F.Paste")
			(net "GND")
		)
		(pad "198" smd rect
			(at 2.050034 -18.275046 270)
			(size 0.519938 1.4986)
			(layers "F.Cu" "F.Mask" "F.Paste")
			(net "M_B_CPU0_SA_CB<3>")
		)
		(pad "199" smd rect
			(at 2.050034 -17.424908 270)
			(size 0.519938 1.4986)
			(layers "F.Cu" "F.Mask" "F.Paste")
			(net "GND")
		)
		(pad "200" smd rect
			(at 2.050034 -16.575024 270)
			(size 0.519938 1.4986)
			(layers "F.Cu" "F.Mask" "F.Paste")
			(net "M_B_CPU0_SA_DQS_DN<9>")
		)
		(pad "201" smd rect
			(at 2.050034 -15.724886 270)
			(size 0.519938 1.4986)
			(layers "F.Cu" "F.Mask" "F.Paste")
			(net "M_B_CPU0_SA_DQS_DP<9>")
		)
		(pad "202" smd rect
			(at 2.050034 -14.875002 270)
			(size 0.519938 1.4986)
			(layers "F.Cu" "F.Mask" "F.Paste")
			(net "GND")
		)
		(pad "203" smd rect
			(at 2.050034 -14.025118 270)
			(size 0.519938 1.4986)
			(layers "F.Cu" "F.Mask" "F.Paste")
			(net "M_B_CPU0_SA_CB<6>")
		)
		(pad "204" smd rect
			(at 2.050034 -13.17498 270)
			(size 0.519938 1.4986)
			(layers "F.Cu" "F.Mask" "F.Paste")
			(net "GND")
		)
		(pad "205" smd rect
			(at 2.050034 -12.325096 270)
			(size 0.519938 1.4986)
			(layers "F.Cu" "F.Mask" "F.Paste")
			(net "M_B_CPU0_SA_CB<7>")
		)
		(pad "206" smd rect
			(at 2.050034 -11.474958 270)
			(size 0.519938 1.4986)
			(layers "F.Cu" "F.Mask" "F.Paste")
			(net "GND")
		)
		(pad "207" smd rect
			(at 2.050034 -10.625074 270)
			(size 0.519938 1.4986)
			(layers "F.Cu" "F.Mask" "F.Paste")
			(net "RST_M_AB_CPU0_FPGA_N")
		)
		(pad "208" smd rect
			(at 2.050034 -9.774936 270)
			(size 0.519938 1.4986)
			(layers "F.Cu" "F.Mask" "F.Paste")
			(net "GND")
		)
		(pad "209" smd rect
			(at 2.050034 -8.925052 270)
			(size 0.519938 1.4986)
			(layers "F.Cu" "F.Mask" "F.Paste")
			(net "M_B_CPU0_SA_CS_N<3>")
		)
		(pad "210" smd rect
			(at 2.050034 -8.074914 270)
			(size 0.519938 1.4986)
			(layers "F.Cu" "F.Mask" "F.Paste")
			(net "GND")
		)
		(pad "211" smd rect
			(at 2.050034 -7.22503 270)
			(size 0.519938 1.4986)
			(layers "F.Cu" "F.Mask" "F.Paste")
			(net "M_B_CPU0_SA_CA<1>")
		)
		(pad "212" smd rect
			(at 2.050034 -6.374892 270)
			(size 0.519938 1.4986)
			(layers "F.Cu" "F.Mask" "F.Paste")
			(net "GND")
		)
		(pad "213" smd rect
			(at 2.050034 -5.525008 270)
			(size 0.519938 1.4986)
			(layers "F.Cu" "F.Mask" "F.Paste")
			(net "M_B_CPU0_SA_CA<3>")
		)
		(pad "214" smd rect
			(at 2.050034 -4.675124 270)
			(size 0.519938 1.4986)
			(layers "F.Cu" "F.Mask" "F.Paste")
			(net "GND")
		)
		(pad "215" smd rect
			(at 2.050034 -3.824986 270)
			(size 0.519938 1.4986)
			(layers "F.Cu" "F.Mask" "F.Paste")
			(net "M_B_CPU0_SA_CA<5>")
		)
		(pad "216" smd rect
			(at 2.050034 -2.975102 270)
			(size 0.519938 1.4986)
			(layers "F.Cu" "F.Mask" "F.Paste")
			(net "GND")
		)
		(pad "217" smd rect
			(at 2.050034 -2.124964 270)
			(size 0.519938 1.4986)
			(layers "F.Cu" "F.Mask" "F.Paste")
			(net "M_B_CPU0_CLK_DP<1>")
		)
		(pad "218" smd rect
			(at 2.050034 -1.27508 270)
			(size 0.519938 1.4986)
			(layers "F.Cu" "F.Mask" "F.Paste")
			(net "M_B_CPU0_CLK_DN<1>")
		)
		(pad "219" smd rect
			(at 2.050034 -0.424942 270)
			(size 0.519938 1.4986)
			(layers "F.Cu" "F.Mask" "F.Paste")
			(net "GND")
		)
		(pad "220" smd rect
			(at 2.050034 5.525008 270)
			(size 0.519938 1.4986)
			(layers "F.Cu" "F.Mask" "F.Paste")
			(net "TP_CHB_CPU0_DIMM2_FRU_4")
		)
		(pad "221" smd rect
			(at 2.050034 6.374892 270)
			(size 0.519938 1.4986)
			(layers "F.Cu" "F.Mask" "F.Paste")
			(net "M_B_CPU0_SB_CA<1>")
		)
		(pad "222" smd rect
			(at 2.050034 7.22503 270)
			(size 0.519938 1.4986)
			(layers "F.Cu" "F.Mask" "F.Paste")
			(net "GND")
		)
		(pad "223" smd rect
			(at 2.050034 8.074914 270)
			(size 0.519938 1.4986)
			(layers "F.Cu" "F.Mask" "F.Paste")
			(net "M_B_CPU0_SB_CA<3>")
		)
		(pad "224" smd rect
			(at 2.050034 8.925052 270)
			(size 0.519938 1.4986)
			(layers "F.Cu" "F.Mask" "F.Paste")
			(net "GND")
		)
	)
)
